(kicad_pcb
	(version 20260206)
	(generator "pcbnew")
	(generator_version "10.0")
	(general
		(thickness 1.6)
		(legacy_teardrops no)
	)
	(paper "A4")
	(title_block
		(title "01162023_DA0F0TEBIF0_F0T_Expander_BD_F_brd_V02_OCP.brd")
		(comment 1 "Grand Teton / footprints 1472-1478 of 9728")
	)
	(layers
		(0 "F.Cu" signal "TOP")
		(4 "In1.Cu" signal "GND")
		(6 "In2.Cu" signal "VCC")
		(8 "In3.Cu" signal "VCC1")
		(10 "In4.Cu" signal "GND1")
		(12 "In5.Cu" signal "IN1")
		(14 "In6.Cu" signal "GND2")
		(16 "In7.Cu" signal "IN2")
		(18 "In8.Cu" signal "GND3")
		(20 "In9.Cu" signal "IN3")
		(22 "In10.Cu" signal "GND4")
		(24 "In11.Cu" signal "IN4")
		(26 "In12.Cu" signal "GND5")
		(28 "In13.Cu" signal "IN5")
		(30 "In14.Cu" signal "GND6")
		(32 "In15.Cu" signal "IN6")
		(34 "In16.Cu" signal "GND7")
		(2 "B.Cu" signal "BOTTOM")
		(9 "F.Adhes" user "F.Adhesive")
		(11 "B.Adhes" user "B.Adhesive")
		(13 "F.Paste" user "Package Geometry/Pastemask Top")
		(15 "B.Paste" user "Package Geometry/Pastemask Bottom")
		(5 "F.SilkS" user "Ref Des/Silkscreen Top")
		(7 "B.SilkS" user "Ref Des/Silkscreen Bottom")
		(1 "F.Mask" user "Board Geometry/Soldermask Top")
		(3 "B.Mask" user "Board Geometry/Soldermask Bottom")
		(17 "Dwgs.User" user "User.Drawings")
		(19 "Cmts.User" user "User.Comments")
		(21 "Eco1.User" user "User.Eco1")
		(23 "Eco2.User" user "User.Eco2")
		(25 "Edge.Cuts" user "Board Geometry/Outline")
		(27 "Margin" user)
		(31 "F.CrtYd" user "Package Geometry/Place Bound Top")
		(29 "B.CrtYd" user "Package Geometry/Place Bound Bottom")
		(35 "F.Fab" user "Ref Des/Assembly Top")
		(33 "B.Fab" user "Ref Des/Assembly Bottom")
	)
	(footprint ""
		(layer "F.Cu")
		(at 358.013 -210.312 180)
		(property "Reference" "R4097"
			(at 0 0 180)
			(layer "F.SilkS")
			(hide yes)
			(effects
				(font
					(size 1.27 1.27)
				)
			)
		)
		(property "Value" ""
			(at 0 0 180)
			(layer "F.Fab")
			(effects
				(font
					(size 1.27 1.27)
				)
			)
		)
		(duplicate_pad_numbers_are_jumpers no)
		(fp_line
			(start 0.7874 0.4064)
			(end -0.7874 0.4064)
			(stroke
				(width 0.1524)
				(type default)
			)
			(layer "F.SilkS")
		)
		(fp_line
			(start 0.7874 -0.4064)
			(end 0.7874 0.4064)
			(stroke
				(width 0.1524)
				(type default)
			)
			(layer "F.SilkS")
		)
		(fp_line
			(start -0.7874 0.4064)
			(end -0.7874 -0.4064)
			(stroke
				(width 0.1524)
				(type default)
			)
			(layer "F.SilkS")
		)
		(fp_line
			(start -0.7874 -0.4064)
			(end 0.7874 -0.4064)
			(stroke
				(width 0.1524)
				(type default)
			)
			(layer "F.SilkS")
		)
		(fp_line
			(start 0.67945 0.3048)
			(end 0.120396 0.3048)
			(stroke
				(width 0.1)
				(type default)
			)
			(layer "F.Fab")
		)
		(fp_line
			(start 0.67945 -0.3048)
			(end 0.67945 0.3048)
			(stroke
				(width 0.1)
				(type default)
			)
			(layer "F.Fab")
		)
		(fp_line
			(start 0.12065 -0.2794)
			(end 0.12065 -0.3048)
			(stroke
				(width 0.1)
				(type default)
			)
			(layer "F.Fab")
		)
		(fp_line
			(start 0.12065 -0.3048)
			(end 0.67945 -0.3048)
			(stroke
				(width 0.1)
				(type default)
			)
			(layer "F.Fab")
		)
		(fp_line
			(start 0.120396 0.3048)
			(end 0.120396 0.2794)
			(stroke
				(width 0.1)
				(type default)
			)
			(layer "F.Fab")
		)
		(fp_line
			(start 0.120396 0.2794)
			(end -0.12065 0.2794)
			(stroke
				(width 0.1)
				(type default)
			)
			(layer "F.Fab")
		)
		(fp_line
			(start -0.12065 0.3048)
			(end -0.67945 0.3048)
			(stroke
				(width 0.1)
				(type default)
			)
			(layer "F.Fab")
		)
		(fp_line
			(start -0.12065 0.2794)
			(end -0.12065 0.3048)
			(stroke
				(width 0.1)
				(type default)
			)
			(layer "F.Fab")
		)
		(fp_line
			(start -0.12065 -0.2794)
			(end 0.12065 -0.2794)
			(stroke
				(width 0.1)
				(type default)
			)
			(layer "F.Fab")
		)
		(fp_line
			(start -0.12065 -0.305054)
			(end -0.12065 -0.2794)
			(stroke
				(width 0.1)
				(type default)
			)
			(layer "F.Fab")
		)
		(fp_line
			(start -0.67945 0.3048)
			(end -0.67945 -0.305054)
			(stroke
				(width 0.1)
				(type default)
			)
			(layer "F.Fab")
		)
		(fp_line
			(start -0.67945 -0.305054)
			(end -0.12065 -0.305054)
			(stroke
				(width 0.1)
				(type default)
			)
			(layer "F.Fab")
		)
		(pad "1" smd circle
			(at -0.40005 0 180)
			(size 0 0)
			(layers "F.Cu" "F.Mask" "F.Paste")
			(net "PRSNT_NIC5_FPGA_R_N")
		)
		(pad "2" smd circle
			(at 0.40005 0 180)
			(size 0 0)
			(layers "F.Cu" "F.Mask" "F.Paste")
			(net "PRSNT_NIC5_FPGA_N")
		)
	)
	(footprint ""
		(layer "F.Cu")
		(at 424.78198 -38.041072 180)
		(property "Reference" "R6121"
			(at 0 0 180)
			(layer "F.SilkS")
			(hide yes)
			(effects
				(font
					(size 1.27 1.27)
				)
			)
		)
		(property "Value" ""
			(at 0 0 180)
			(layer "F.Fab")
			(effects
				(font
					(size 1.27 1.27)
				)
			)
		)
		(duplicate_pad_numbers_are_jumpers no)
		(fp_line
			(start 0.7874 0.4064)
			(end -0.7874 0.4064)
			(stroke
				(width 0.1524)
				(type default)
			)
			(layer "F.SilkS")
		)
		(fp_line
			(start 0.7874 -0.4064)
			(end 0.7874 0.4064)
			(stroke
				(width 0.1524)
				(type default)
			)
			(layer "F.SilkS")
		)
		(fp_line
			(start -0.7874 0.4064)
			(end -0.7874 -0.4064)
			(stroke
				(width 0.1524)
				(type default)
			)
			(layer "F.SilkS")
		)
		(fp_line
			(start -0.7874 -0.4064)
			(end 0.7874 -0.4064)
			(stroke
				(width 0.1524)
				(type default)
			)
			(layer "F.SilkS")
		)
		(fp_line
			(start 0.67945 0.3048)
			(end 0.120396 0.3048)
			(stroke
				(width 0.1)
				(type default)
			)
			(layer "F.Fab")
		)
		(fp_line
			(start 0.67945 -0.3048)
			(end 0.67945 0.3048)
			(stroke
				(width 0.1)
				(type default)
			)
			(layer "F.Fab")
		)
		(fp_line
			(start 0.12065 -0.2794)
			(end 0.12065 -0.3048)
			(stroke
				(width 0.1)
				(type default)
			)
			(layer "F.Fab")
		)
		(fp_line
			(start 0.12065 -0.3048)
			(end 0.67945 -0.3048)
			(stroke
				(width 0.1)
				(type default)
			)
			(layer "F.Fab")
		)
		(fp_line
			(start 0.120396 0.3048)
			(end 0.120396 0.2794)
			(stroke
				(width 0.1)
				(type default)
			)
			(layer "F.Fab")
		)
		(fp_line
			(start 0.120396 0.2794)
			(end -0.12065 0.2794)
			(stroke
				(width 0.1)
				(type default)
			)
			(layer "F.Fab")
		)
		(fp_line
			(start -0.12065 0.3048)
			(end -0.67945 0.3048)
			(stroke
				(width 0.1)
				(type default)
			)
			(layer "F.Fab")
		)
		(fp_line
			(start -0.12065 0.2794)
			(end -0.12065 0.3048)
			(stroke
				(width 0.1)
				(type default)
			)
			(layer "F.Fab")
		)
		(fp_line
			(start -0.12065 -0.2794)
			(end 0.12065 -0.2794)
			(stroke
				(width 0.1)
				(type default)
			)
			(layer "F.Fab")
		)
		(fp_line
			(start -0.12065 -0.305054)
			(end -0.12065 -0.2794)
			(stroke
				(width 0.1)
				(type default)
			)
			(layer "F.Fab")
		)
		(fp_line
			(start -0.67945 0.3048)
			(end -0.67945 -0.305054)
			(stroke
				(width 0.1)
				(type default)
			)
			(layer "F.Fab")
		)
		(fp_line
			(start -0.67945 -0.305054)
			(end -0.12065 -0.305054)
			(stroke
				(width 0.1)
				(type default)
			)
			(layer "F.Fab")
		)
		(pad "1" smd circle
			(at -0.40005 0 180)
			(size 0 0)
			(layers "F.Cu" "F.Mask" "F.Paste")
			(net "P5V_AUX")
		)
		(pad "2" smd circle
			(at 0.40005 0 180)
			(size 0 0)
			(layers "F.Cu" "F.Mask" "F.Paste")
			(net "P3V3_SSD15_PG_G2")
		)
	)
	(footprint ""
		(layer "F.Cu")
		(at 86.218522 -350.098614 90)
		(property "Reference" "C103"
			(at 0 0 90)
			(layer "F.SilkS")
			(hide yes)
			(effects
				(font
					(size 1.27 1.27)
				)
			)
		)
		(property "Value" ""
			(at 0 0 90)
			(layer "F.Fab")
			(effects
				(font
					(size 1.27 1.27)
				)
			)
		)
		(duplicate_pad_numbers_are_jumpers no)
		(fp_line
			(start 0.299974 -0.150114)
			(end 0.299974 0.150114)
			(stroke
				(width 0.1)
				(type default)
			)
			(layer "F.Fab")
		)
		(fp_line
			(start -0.299974 -0.150114)
			(end 0.299974 -0.150114)
			(stroke
				(width 0.1)
				(type default)
			)
			(layer "F.Fab")
		)
		(fp_line
			(start 0.299974 0.150114)
			(end -0.299974 0.150114)
			(stroke
				(width 0.1)
				(type default)
			)
			(layer "F.Fab")
		)
		(fp_line
			(start -0.299974 0.150114)
			(end -0.299974 -0.150114)
			(stroke
				(width 0.1)
				(type default)
			)
			(layer "F.Fab")
		)
		(pad "1" smd rect
			(at -0.2667 0 90)
			(size 0.3048 0.381)
			(layers "F.Cu" "F.Mask" "F.Paste")
			(net "P5E_PEX0_STN5_TX_DP<92>")
		)
		(pad "2" smd rect
			(at 0.2667 0 90)
			(size 0.3048 0.381)
			(layers "F.Cu" "F.Mask" "F.Paste")
			(net "P5E_PEX0_STN5_TX_C_DP<92>")
		)
	)
	(footprint ""
		(layer "F.Cu")
		(at 87.749634 -300.60265 90)
		(property "Reference" "R6387"
			(at 0 0 90)
			(layer "F.SilkS")
			(hide yes)
			(effects
				(font
					(size 1.27 1.27)
				)
			)
		)
		(property "Value" ""
			(at 0 0 90)
			(layer "F.Fab")
			(effects
				(font
					(size 1.27 1.27)
				)
			)
		)
		(duplicate_pad_numbers_are_jumpers no)
		(fp_line
			(start 0.7874 -0.4064)
			(end 0.7874 0.4064)
			(stroke
				(width 0.1524)
				(type default)
			)
			(layer "F.SilkS")
		)
		(fp_line
			(start -0.7874 -0.4064)
			(end 0.7874 -0.4064)
			(stroke
				(width 0.1524)
				(type default)
			)
			(layer "F.SilkS")
		)
		(fp_line
			(start 0.7874 0.4064)
			(end -0.7874 0.4064)
			(stroke
				(width 0.1524)
				(type default)
			)
			(layer "F.SilkS")
		)
		(fp_line
			(start -0.7874 0.4064)
			(end -0.7874 -0.4064)
			(stroke
				(width 0.1524)
				(type default)
			)
			(layer "F.SilkS")
		)
		(fp_line
			(start -0.12065 -0.305054)
			(end -0.12065 -0.2794)
			(stroke
				(width 0.1)
				(type default)
			)
			(layer "F.Fab")
		)
		(fp_line
			(start -0.67945 -0.305054)
			(end -0.12065 -0.305054)
			(stroke
				(width 0.1)
				(type default)
			)
			(layer "F.Fab")
		)
		(fp_line
			(start 0.67945 -0.3048)
			(end 0.67945 0.3048)
			(stroke
				(width 0.1)
				(type default)
			)
			(layer "F.Fab")
		)
		(fp_line
			(start 0.12065 -0.3048)
			(end 0.67945 -0.3048)
			(stroke
				(width 0.1)
				(type default)
			)
			(layer "F.Fab")
		)
		(fp_line
			(start 0.12065 -0.2794)
			(end 0.12065 -0.3048)
			(stroke
				(width 0.1)
				(type default)
			)
			(layer "F.Fab")
		)
		(fp_line
			(start -0.12065 -0.2794)
			(end 0.12065 -0.2794)
			(stroke
				(width 0.1)
				(type default)
			)
			(layer "F.Fab")
		)
		(fp_line
			(start 0.120396 0.2794)
			(end -0.12065 0.2794)
			(stroke
				(width 0.1)
				(type default)
			)
			(layer "F.Fab")
		)
		(fp_line
			(start -0.12065 0.2794)
			(end -0.12065 0.3048)
			(stroke
				(width 0.1)
				(type default)
			)
			(layer "F.Fab")
		)
		(fp_line
			(start 0.67945 0.3048)
			(end 0.120396 0.3048)
			(stroke
				(width 0.1)
				(type default)
			)
			(layer "F.Fab")
		)
		(fp_line
			(start 0.120396 0.3048)
			(end 0.120396 0.2794)
			(stroke
				(width 0.1)
				(type default)
			)
			(layer "F.Fab")
		)
		(fp_line
			(start -0.12065 0.3048)
			(end -0.67945 0.3048)
			(stroke
				(width 0.1)
				(type default)
			)
			(layer "F.Fab")
		)
		(fp_line
			(start -0.67945 0.3048)
			(end -0.67945 -0.305054)
			(stroke
				(width 0.1)
				(type default)
			)
			(layer "F.Fab")
		)
		(pad "1" smd circle
			(at -0.40005 0 90)
			(size 0 0)
			(layers "F.Cu" "F.Mask" "F.Paste")
			(net "RST_PEX0_S1_PERST_N")
		)
		(pad "2" smd circle
			(at 0.40005 0 90)
			(size 0 0)
			(layers "F.Cu" "F.Mask" "F.Paste")
			(net "RST_PEX0_S1_PERST_R_N")
		)
	)
	(footprint ""
		(layer "F.Cu")
		(at 281.856434 -17.419574 180)
		(property "Reference" "R1691"
			(at 0 0 180)
			(layer "F.SilkS")
			(hide yes)
			(effects
				(font
					(size 1.27 1.27)
				)
			)
		)
		(property "Value" ""
			(at 0 0 180)
			(layer "F.Fab")
			(effects
				(font
					(size 1.27 1.27)
				)
			)
		)
		(duplicate_pad_numbers_are_jumpers no)
		(fp_line
			(start 0.7874 0.4064)
			(end -0.7874 0.4064)
			(stroke
				(width 0.1524)
				(type default)
			)
			(layer "F.SilkS")
		)
		(fp_line
			(start 0.7874 -0.4064)
			(end 0.7874 0.4064)
			(stroke
				(width 0.1524)
				(type default)
			)
			(layer "F.SilkS")
		)
		(fp_line
			(start -0.7874 0.4064)
			(end -0.7874 -0.4064)
			(stroke
				(width 0.1524)
				(type default)
			)
			(layer "F.SilkS")
		)
		(fp_line
			(start -0.7874 -0.4064)
			(end 0.7874 -0.4064)
			(stroke
				(width 0.1524)
				(type default)
			)
			(layer "F.SilkS")
		)
		(fp_line
			(start 0.67945 0.3048)
			(end 0.120396 0.3048)
			(stroke
				(width 0.1)
				(type default)
			)
			(layer "F.Fab")
		)
		(fp_line
			(start 0.67945 -0.3048)
			(end 0.67945 0.3048)
			(stroke
				(width 0.1)
				(type default)
			)
			(layer "F.Fab")
		)
		(fp_line
			(start 0.12065 -0.2794)
			(end 0.12065 -0.3048)
			(stroke
				(width 0.1)
				(type default)
			)
			(layer "F.Fab")
		)
		(fp_line
			(start 0.12065 -0.3048)
			(end 0.67945 -0.3048)
			(stroke
				(width 0.1)
				(type default)
			)
			(layer "F.Fab")
		)
		(fp_line
			(start 0.120396 0.3048)
			(end 0.120396 0.2794)
			(stroke
				(width 0.1)
				(type default)
			)
			(layer "F.Fab")
		)
		(fp_line
			(start 0.120396 0.2794)
			(end -0.12065 0.2794)
			(stroke
				(width 0.1)
				(type default)
			)
			(layer "F.Fab")
		)
		(fp_line
			(start -0.12065 0.3048)
			(end -0.67945 0.3048)
			(stroke
				(width 0.1)
				(type default)
			)
			(layer "F.Fab")
		)
		(fp_line
			(start -0.12065 0.2794)
			(end -0.12065 0.3048)
			(stroke
				(width 0.1)
				(type default)
			)
			(layer "F.Fab")
		)
		(fp_line
			(start -0.12065 -0.2794)
			(end 0.12065 -0.2794)
			(stroke
				(width 0.1)
				(type default)
			)
			(layer "F.Fab")
		)
		(fp_line
			(start -0.12065 -0.305054)
			(end -0.12065 -0.2794)
			(stroke
				(width 0.1)
				(type default)
			)
			(layer "F.Fab")
		)
		(fp_line
			(start -0.67945 0.3048)
			(end -0.67945 -0.305054)
			(stroke
				(width 0.1)
				(type default)
			)
			(layer "F.Fab")
		)
		(fp_line
			(start -0.67945 -0.305054)
			(end -0.12065 -0.305054)
			(stroke
				(width 0.1)
				(type default)
			)
			(layer "F.Fab")
		)
		(pad "1" smd circle
			(at -0.40005 0 180)
			(size 0 0)
			(layers "F.Cu" "F.Mask" "F.Paste")
			(net "P3V3_SSD9")
		)
		(pad "2" smd circle
			(at 0.40005 0 180)
			(size 0 0)
			(layers "F.Cu" "F.Mask" "F.Paste")
			(net "SMB_ISO_SSD9_SCL")
		)
	)
	(footprint ""
		(layer "F.Cu")
		(at 423.96791 -19.453098)
		(property "Reference" "R1737"
			(at 0 0 0)
			(layer "F.SilkS")
			(hide yes)
			(effects
				(font
					(size 1.27 1.27)
				)
			)
		)
		(property "Value" ""
			(at 0 0 0)
			(layer "F.Fab")
			(effects
				(font
					(size 1.27 1.27)
				)
			)
		)
		(duplicate_pad_numbers_are_jumpers no)
		(fp_line
			(start -0.7874 -0.4064)
			(end 0.7874 -0.4064)
			(stroke
				(width 0.1524)
				(type default)
			)
			(layer "F.SilkS")
		)
		(fp_line
			(start -0.7874 0.4064)
			(end -0.7874 -0.4064)
			(stroke
				(width 0.1524)
				(type default)
			)
			(layer "F.SilkS")
		)
		(fp_line
			(start 0.7874 -0.4064)
			(end 0.7874 0.4064)
			(stroke
				(width 0.1524)
				(type default)
			)
			(layer "F.SilkS")
		)
		(fp_line
			(start 0.7874 0.4064)
			(end -0.7874 0.4064)
			(stroke
				(width 0.1524)
				(type default)
			)
			(layer "F.SilkS")
		)
		(fp_line
			(start -0.67945 -0.305054)
			(end -0.12065 -0.305054)
			(stroke
				(width 0.1)
				(type default)
			)
			(layer "F.Fab")
		)
		(fp_line
			(start -0.67945 0.3048)
			(end -0.67945 -0.305054)
			(stroke
				(width 0.1)
				(type default)
			)
			(layer "F.Fab")
		)
		(fp_line
			(start -0.12065 -0.305054)
			(end -0.12065 -0.2794)
			(stroke
				(width 0.1)
				(type default)
			)
			(layer "F.Fab")
		)
		(fp_line
			(start -0.12065 -0.2794)
			(end 0.12065 -0.2794)
			(stroke
				(width 0.1)
				(type default)
			)
			(layer "F.Fab")
		)
		(fp_line
			(start -0.12065 0.2794)
			(end -0.12065 0.3048)
			(stroke
				(width 0.1)
				(type default)
			)
			(layer "F.Fab")
		)
		(fp_line
			(start -0.12065 0.3048)
			(end -0.67945 0.3048)
			(stroke
				(width 0.1)
				(type default)
			)
			(layer "F.Fab")
		)
		(fp_line
			(start 0.120396 0.2794)
			(end -0.12065 0.2794)
			(stroke
				(width 0.1)
				(type default)
			)
			(layer "F.Fab")
		)
		(fp_line
			(start 0.120396 0.3048)
			(end 0.120396 0.2794)
			(stroke
				(width 0.1)
				(type default)
			)
			(layer "F.Fab")
		)
		(fp_line
			(start 0.12065 -0.3048)
			(end 0.67945 -0.3048)
			(stroke
				(width 0.1)
				(type default)
			)
			(layer "F.Fab")
		)
		(fp_line
			(start 0.12065 -0.2794)
			(end 0.12065 -0.3048)
			(stroke
				(width 0.1)
				(type default)
			)
			(layer "F.Fab")
		)
		(fp_line
			(start 0.67945 -0.3048)
			(end 0.67945 0.3048)
			(stroke
				(width 0.1)
				(type default)
			)
			(layer "F.Fab")
		)
		(fp_line
			(start 0.67945 0.3048)
			(end 0.120396 0.3048)
			(stroke
				(width 0.1)
				(type default)
			)
			(layer "F.Fab")
		)
		(pad "1" smd circle
			(at -0.40005 0)
			(size 0 0)
			(layers "F.Cu" "F.Mask" "F.Paste")
			(net "SMB_ISO_SSD14_R_SDA")
		)
		(pad "2" smd circle
			(at 0.40005 0)
			(size 0 0)
			(layers "F.Cu" "F.Mask" "F.Paste")
			(net "SMB_ISO_SSD14_SDA")
		)
	)
	(footprint ""
		(layer "F.Cu")
		(at 123.87199 -24.807418)
		(property "Reference" "R422"
			(at 0 0 0)
			(layer "F.SilkS")
			(hide yes)
			(effects
				(font
					(size 1.27 1.27)
				)
			)
		)
		(property "Value" ""
			(at 0 0 0)
			(layer "F.Fab")
			(effects
				(font
					(size 1.27 1.27)
				)
			)
		)
		(duplicate_pad_numbers_are_jumpers no)
		(fp_line
			(start -0.7874 -0.4064)
			(end 0.7874 -0.4064)
			(stroke
				(width 0.1524)
				(type default)
			)
			(layer "F.SilkS")
		)
		(fp_line
			(start -0.7874 0.4064)
			(end -0.7874 -0.4064)
			(stroke
				(width 0.1524)
				(type default)
			)
			(layer "F.SilkS")
		)
		(fp_line
			(start 0.7874 -0.4064)
			(end 0.7874 0.4064)
			(stroke
				(width 0.1524)
				(type default)
			)
			(layer "F.SilkS")
		)
		(fp_line
			(start 0.7874 0.4064)
			(end -0.7874 0.4064)
			(stroke
				(width 0.1524)
				(type default)
			)
			(layer "F.SilkS")
		)
		(fp_line
			(start -0.67945 -0.305054)
			(end -0.12065 -0.305054)
			(stroke
				(width 0.1)
				(type default)
			)
			(layer "F.Fab")
		)
		(fp_line
			(start -0.67945 0.3048)
			(end -0.67945 -0.305054)
			(stroke
				(width 0.1)
				(type default)
			)
			(layer "F.Fab")
		)
		(fp_line
			(start -0.12065 -0.305054)
			(end -0.12065 -0.2794)
			(stroke
				(width 0.1)
				(type default)
			)
			(layer "F.Fab")
		)
		(fp_line
			(start -0.12065 -0.2794)
			(end 0.12065 -0.2794)
			(stroke
				(width 0.1)
				(type default)
			)
			(layer "F.Fab")
		)
		(fp_line
			(start -0.12065 0.2794)
			(end -0.12065 0.3048)
			(stroke
				(width 0.1)
				(type default)
			)
			(layer "F.Fab")
		)
		(fp_line
			(start -0.12065 0.3048)
			(end -0.67945 0.3048)
			(stroke
				(width 0.1)
				(type default)
			)
			(layer "F.Fab")
		)
		(fp_line
			(start 0.120396 0.2794)
			(end -0.12065 0.2794)
			(stroke
				(width 0.1)
				(type default)
			)
			(layer "F.Fab")
		)
		(fp_line
			(start 0.120396 0.3048)
			(end 0.120396 0.2794)
			(stroke
				(width 0.1)
				(type default)
			)
			(layer "F.Fab")
		)
		(fp_line
			(start 0.12065 -0.3048)
			(end 0.67945 -0.3048)
			(stroke
				(width 0.1)
				(type default)
			)
			(layer "F.Fab")
		)
		(fp_line
			(start 0.12065 -0.2794)
			(end 0.12065 -0.3048)
			(stroke
				(width 0.1)
				(type default)
			)
			(layer "F.Fab")
		)
		(fp_line
			(start 0.67945 -0.3048)
			(end 0.67945 0.3048)
			(stroke
				(width 0.1)
				(type default)
			)
			(layer "F.Fab")
		)
		(fp_line
			(start 0.67945 0.3048)
			(end 0.120396 0.3048)
			(stroke
				(width 0.1)
				(type default)
			)
			(layer "F.Fab")
		)
		(pad "1" smd circle
			(at -0.40005 0)
			(size 0 0)
			(layers "F.Cu" "F.Mask" "F.Paste")
			(net "P3V3_SSD4")
		)
		(pad "2" smd circle
			(at 0.40005 0)
			(size 0 0)
			(layers "F.Cu" "F.Mask" "F.Paste")
			(net "PU_CLKREQ4")
		)
	)
)
